# T6G (Grand Teton) — schematic netlist excerpt (pin names and nets, part order shuffled) for the footprints in the layout excerpt that follows; sources: Cadence DE-HDL packaged netlist, KiCad conversion of 04192023_DAF0TMB3IC0_F0TG_MB_C_brd_V02_OCP.brd

R4453  Q_RES  47K 0.1% EMPTY  pkg 0402LF  page 176 : A = RST_USB_CPU0_HUB1_R_N ; B = GND
R6298  Q_RES  10K 1% CHIP  pkg 0402LF  page 178 : A = P3V3_AUX ; B = USB_HUB2_MRP_I2C_SLV_CFG1

(kicad_pcb
	(version 20260206)
	(generator "pcbnew")
	(generator_version "10.0")
	(general
		(thickness 1.6)
		(legacy_teardrops no)
	)
	(paper "A4")
	(title_block
		(title "04192023_DAF0TMB3IC0_F0TG_MB_C_brd_V02_OCP.brd")
		(comment 1 "Grand Teton / footprints 795-796 of 8354")
	)
	(layers
		(0 "F.Cu" signal "TOP")
		(4 "In1.Cu" signal "GND")
		(6 "In2.Cu" signal "IN1")
		(8 "In3.Cu" signal "GND1")
		(10 "In4.Cu" signal "IN2")
		(12 "In5.Cu" signal "GND2")
		(14 "In6.Cu" signal "IN3")
		(16 "In7.Cu" signal "GND3")
		(18 "In8.Cu" signal "VCC")
		(20 "In9.Cu" signal "VCC1")
		(22 "In10.Cu" signal "GND4")
		(24 "In11.Cu" signal "IN4")
		(26 "In12.Cu" signal "GND5")
		(28 "In13.Cu" signal "IN5")
		(30 "In14.Cu" signal "GND6")
		(32 "In15.Cu" signal "IN6")
		(34 "In16.Cu" signal "GND7")
		(2 "B.Cu" signal "BOTTOM")
		(9 "F.Adhes" user "F.Adhesive")
		(11 "B.Adhes" user "B.Adhesive")
		(13 "F.Paste" user "Package Geometry/Pastemask Top")
		(15 "B.Paste" user "Package Geometry/Pastemask Bottom")
		(5 "F.SilkS" user "Ref Des/Silkscreen Top")
		(7 "B.SilkS" user "Ref Des/Silkscreen Bottom")
		(1 "F.Mask" user "Board Geometry/Soldermask Top")
		(3 "B.Mask" user "Board Geometry/Soldermask Bottom")
		(17 "Dwgs.User" user "User.Drawings")
		(19 "Cmts.User" user "User.Comments")
		(21 "Eco1.User" user "User.Eco1")
		(23 "Eco2.User" user "User.Eco2")
		(25 "Edge.Cuts" user "Board Geometry/Outline")
		(27 "Margin" user)
		(31 "F.CrtYd" user "Package Geometry/Place Bound Top")
		(29 "B.CrtYd" user "Package Geometry/Place Bound Bottom")
		(35 "F.Fab" user "Ref Des/Assembly Top")
		(33 "B.Fab" user "Ref Des/Assembly Bottom")
	)
	(footprint ""
		(layer "F.Cu")
		(at 118.617746 -53.49748 180)
		(property "Reference" "R6298"
			(at 0 0 180)
			(layer "F.SilkS")
			(hide yes)
			(effects
				(font
					(size 1.27 1.27)
				)
			)
		)
		(property "Value" ""
			(at 0 0 180)
			(layer "F.Fab")
			(effects
				(font
					(size 1.27 1.27)
				)
			)
		)
		(duplicate_pad_numbers_are_jumpers no)
		(fp_line
			(start 0.7874 0.4064)
			(end -0.7874 0.4064)
			(stroke
				(width 0.1524)
				(type default)
			)
			(layer "F.SilkS")
		)
		(fp_line
			(start 0.7874 -0.4064)
			(end 0.7874 0.4064)
			(stroke
				(width 0.1524)
				(type default)
			)
			(layer "F.SilkS")
		)
		(fp_line
			(start -0.7874 0.4064)
			(end -0.7874 -0.4064)
			(stroke
				(width 0.1524)
				(type default)
			)
			(layer "F.SilkS")
		)
		(fp_line
			(start -0.7874 -0.4064)
			(end 0.7874 -0.4064)
			(stroke
				(width 0.1524)
				(type default)
			)
			(layer "F.SilkS")
		)
		(fp_line
			(start 0.67945 0.3048)
			(end 0.120396 0.3048)
			(stroke
				(width 0.1)
				(type default)
			)
			(layer "F.Fab")
		)
		(fp_line
			(start 0.67945 -0.3048)
			(end 0.67945 0.3048)
			(stroke
				(width 0.1)
				(type default)
			)
			(layer "F.Fab")
		)
		(fp_line
			(start 0.12065 -0.2794)
			(end 0.12065 -0.3048)
			(stroke
				(width 0.1)
				(type default)
			)
			(layer "F.Fab")
		)
		(fp_line
			(start 0.12065 -0.3048)
			(end 0.67945 -0.3048)
			(stroke
				(width 0.1)
				(type default)
			)
			(layer "F.Fab")
		)
		(fp_line
			(start 0.120396 0.3048)
			(end 0.120396 0.2794)
			(stroke
				(width 0.1)
				(type default)
			)
			(layer "F.Fab")
		)
		(fp_line
			(start 0.120396 0.2794)
			(end -0.12065 0.2794)
			(stroke
				(width 0.1)
				(type default)
			)
			(layer "F.Fab")
		)
		(fp_line
			(start -0.12065 0.3048)
			(end -0.67945 0.3048)
			(stroke
				(width 0.1)
				(type default)
			)
			(layer "F.Fab")
		)
		(fp_line
			(start -0.12065 0.2794)
			(end -0.12065 0.3048)
			(stroke
				(width 0.1)
				(type default)
			)
			(layer "F.Fab")
		)
		(fp_line
			(start -0.12065 -0.2794)
			(end 0.12065 -0.2794)
			(stroke
				(width 0.1)
				(type default)
			)
			(layer "F.Fab")
		)
		(fp_line
			(start -0.12065 -0.305054)
			(end -0.12065 -0.2794)
			(stroke
				(width 0.1)
				(type default)
			)
			(layer "F.Fab")
		)
		(fp_line
			(start -0.67945 0.3048)
			(end -0.67945 -0.305054)
			(stroke
				(width 0.1)
				(type default)
			)
			(layer "F.Fab")
		)
		(fp_line
			(start -0.67945 -0.305054)
			(end -0.12065 -0.305054)
			(stroke
				(width 0.1)
				(type default)
			)
			(layer "F.Fab")
		)
		(pad "1" smd circle
			(at -0.40005 0 180)
			(size 0 0)
			(layers "F.Cu" "F.Mask" "F.Paste")
			(net "P3V3_AUX")
		)
		(pad "2" smd circle
			(at 0.40005 0 180)
			(size 0 0)
			(layers "F.Cu" "F.Mask" "F.Paste")
			(net "USB_HUB2_MRP_I2C_SLV_CFG1")
		)
	)
	(footprint ""
		(layer "F.Cu")
		(at 124.633228 -50.169064 180)
		(property "Reference" "R4453"
			(at 0 0 180)
			(layer "F.SilkS")
			(hide yes)
			(effects
				(font
					(size 1.27 1.27)
				)
			)
		)
		(property "Value" ""
			(at 0 0 180)
			(layer "F.Fab")
			(effects
				(font
					(size 1.27 1.27)
				)
			)
		)
		(duplicate_pad_numbers_are_jumpers no)
		(fp_line
			(start 0.7874 0.4064)
			(end -0.7874 0.4064)
			(stroke
				(width 0.1524)
				(type default)
			)
			(layer "F.SilkS")
		)
		(fp_line
			(start 0.7874 -0.4064)
			(end 0.7874 0.4064)
			(stroke
				(width 0.1524)
				(type default)
			)
			(layer "F.SilkS")
		)
		(fp_line
			(start -0.7874 0.4064)
			(end -0.7874 -0.4064)
			(stroke
				(width 0.1524)
				(type default)
			)
			(layer "F.SilkS")
		)
		(fp_line
			(start -0.7874 -0.4064)
			(end 0.7874 -0.4064)
			(stroke
				(width 0.1524)
				(type default)
			)
			(layer "F.SilkS")
		)
		(fp_line
			(start 0.67945 0.3048)
			(end 0.120396 0.3048)
			(stroke
				(width 0.1)
				(type default)
			)
			(layer "F.Fab")
		)
		(fp_line
			(start 0.67945 -0.3048)
			(end 0.67945 0.3048)
			(stroke
				(width 0.1)
				(type default)
			)
			(layer "F.Fab")
		)
		(fp_line
			(start 0.12065 -0.2794)
			(end 0.12065 -0.3048)
			(stroke
				(width 0.1)
				(type default)
			)
			(layer "F.Fab")
		)
		(fp_line
			(start 0.12065 -0.3048)
			(end 0.67945 -0.3048)
			(stroke
				(width 0.1)
				(type default)
			)
			(layer "F.Fab")
		)
		(fp_line
			(start 0.120396 0.3048)
			(end 0.120396 0.2794)
			(stroke
				(width 0.1)
				(type default)
			)
			(layer "F.Fab")
		)
		(fp_line
			(start 0.120396 0.2794)
			(end -0.12065 0.2794)
			(stroke
				(width 0.1)
				(type default)
			)
			(layer "F.Fab")
		)
		(fp_line
			(start -0.12065 0.3048)
			(end -0.67945 0.3048)
			(stroke
				(width 0.1)
				(type default)
			)
			(layer "F.Fab")
		)
		(fp_line
			(start -0.12065 0.2794)
			(end -0.12065 0.3048)
			(stroke
				(width 0.1)
				(type default)
			)
			(layer "F.Fab")
		)
		(fp_line
			(start -0.12065 -0.2794)
			(end 0.12065 -0.2794)
			(stroke
				(width 0.1)
				(type default)
			)
			(layer "F.Fab")
		)
		(fp_line
			(start -0.12065 -0.305054)
			(end -0.12065 -0.2794)
			(stroke
				(width 0.1)
				(type default)
			)
			(layer "F.Fab")
		)
		(fp_line
			(start -0.67945 0.3048)
			(end -0.67945 -0.305054)
			(stroke
				(width 0.1)
				(type default)
			)
			(layer "F.Fab")
		)
		(fp_line
			(start -0.67945 -0.305054)
			(end -0.12065 -0.305054)
			(stroke
				(width 0.1)
				(type default)
			)
			(layer "F.Fab")
		)
		(pad "1" smd circle
			(at -0.40005 0 180)
			(size 0 0)
			(layers "F.Cu" "F.Mask" "F.Paste")
			(net "RST_USB_CPU0_HUB1_R_N")
		)
		(pad "2" smd circle
			(at 0.40005 0 180)
			(size 0 0)
			(layers "F.Cu" "F.Mask" "F.Paste")
			(net "GND")
		)
	)
)
